(kicad_pcb
	(version 20260206)
	(generator "pcbnew")
	(generator_version "10.0")
	(general
		(thickness 1.6)
		(legacy_teardrops no)
	)
	(paper "A4")
	(title_block
		(title "Wiwynn_Tioga_Pass_MB.brd")
		(comment 1 "Tioga Pass / footprints 3357-3364 of 4770")
	)
	(layers
		(0 "F.Cu" signal "TOP")
		(4 "In1.Cu" signal "L2GND")
		(6 "In2.Cu" signal "L3")
		(8 "In3.Cu" signal "L4GND")
		(10 "In4.Cu" signal "L5")
		(12 "In5.Cu" signal "L6GND")
		(14 "In6.Cu" signal "L7VCC")
		(16 "In7.Cu" signal "L8VCC")
		(18 "In8.Cu" signal "L9GND")
		(20 "In9.Cu" signal "L10")
		(22 "In10.Cu" signal "L11GND")
		(24 "In11.Cu" signal "L12")
		(26 "In12.Cu" signal "L13GND")
		(2 "B.Cu" signal "BOTTOM")
		(9 "F.Adhes" user "F.Adhesive")
		(11 "B.Adhes" user "B.Adhesive")
		(13 "F.Paste" user "Package Geometry/Pastemask Top")
		(15 "B.Paste" user "Package Geometry/Pastemask Bottom")
		(5 "F.SilkS" user "Ref Des/Silkscreen Top")
		(7 "B.SilkS" user "Ref Des/Silkscreen Bottom")
		(1 "F.Mask" user "Board Geometry/Soldermask Top")
		(3 "B.Mask" user "Board Geometry/Soldermask Bottom")
		(17 "Dwgs.User" user "User.Drawings")
		(19 "Cmts.User" user "User.Comments")
		(21 "Eco1.User" user "User.Eco1")
		(23 "Eco2.User" user "User.Eco2")
		(25 "Edge.Cuts" user "Board Geometry/Outline")
		(27 "Margin" user)
		(31 "F.CrtYd" user "Package Geometry/Place Bound Top")
		(29 "B.CrtYd" user "Package Geometry/Place Bound Bottom")
		(35 "F.Fab" user "Ref Des/Assembly Top")
		(33 "B.Fab" user "Ref Des/Assembly Bottom")
	)
	(footprint ""
		(layer "B.Cu")
		(at 349.2246 -147.715224 -90)
		(property "Reference" "R3L8"
			(at 0 0 90)
			(layer "B.SilkS")
			(hide yes)
			(effects
				(font
					(size 1.27 1.27)
				)
				(justify mirror)
			)
		)
		(property "Value" ""
			(at 0 0 90)
			(layer "B.Fab")
			(effects
				(font
					(size 1.27 1.27)
				)
				(justify mirror)
			)
		)
		(duplicate_pad_numbers_are_jumpers no)
		(fp_poly
			(pts
				(xy 0.2794 -0.1016) (xy -0.2794 -0.1016) (xy -0.2794 0.9906) (xy 0.2794 0.9906)
			)
			(stroke
				(width 0)
				(type default)
			)
			(fill no)
			(layer "B.CrtYd")
		)
		(fp_line
			(start -0.2794 0.9906)
			(end -0.2794 -0.1016)
			(stroke
				(width 0.1)
				(type default)
			)
			(layer "B.Fab")
		)
		(fp_line
			(start 0.2794 0.9906)
			(end -0.2794 0.9906)
			(stroke
				(width 0.1)
				(type default)
			)
			(layer "B.Fab")
		)
		(fp_line
			(start -0.2794 -0.1016)
			(end 0.2794 -0.1016)
			(stroke
				(width 0.1)
				(type default)
			)
			(layer "B.Fab")
		)
		(fp_line
			(start 0.2794 -0.1016)
			(end 0.2794 0.9906)
			(stroke
				(width 0.1)
				(type default)
			)
			(layer "B.Fab")
		)
		(pad "1" smd rect
			(at 0 0 90)
			(size 0.508 0.508)
			(layers "B.Cu" "B.Mask" "B.Paste")
			(net "VR_PVDDQ_DEF_PH2_VCIN")
		)
		(pad "2" smd rect
			(at 0 0.889 90)
			(size 0.508 0.508)
			(layers "B.Cu" "B.Mask" "B.Paste")
			(net "P5V_STBY")
		)
		(zone
			(layer "B.Cu")
			(hatch none 0.5)
			(connect_pads
				(clearance 0)
			)
			(min_thickness 0.25)
			(keepout
				(tracks not_allowed)
				(vias allowed)
				(pads allowed)
				(copperpour not_allowed)
				(footprints allowed)
			)
			(placement
				(enabled no)
				(sheetname "")
			)
			(fill
				(thermal_gap 0.5)
				(thermal_bridge_width 0.5)
				(island_removal_mode 0)
			)
			(polygon
				(pts
					(xy 348.5896 -147.461224) (xy 348.5896 -147.969224) (xy 348.9706 -147.969224) (xy 348.9706 -147.461224)
				)
			)
		)
		(zone
			(layer "B.Cu")
			(hatch none 0.5)
			(connect_pads
				(clearance 0)
			)
			(min_thickness 0.25)
			(keepout
				(tracks allowed)
				(vias not_allowed)
				(pads allowed)
				(copperpour not_allowed)
				(footprints allowed)
			)
			(placement
				(enabled no)
				(sheetname "")
			)
			(fill
				(thermal_gap 0.5)
				(thermal_bridge_width 0.5)
				(island_removal_mode 0)
			)
			(polygon
				(pts
					(xy 348.9706 -147.461224) (xy 348.9706 -147.969224) (xy 348.5896 -147.969224) (xy 348.5896 -147.461224)
				)
			)
		)
	)
	(footprint ""
		(layer "B.Cu")
		(at 487.357674 -52.946046 -90)
		(property "Reference" "F25W1"
			(at 0 0 90)
			(layer "B.SilkS")
			(hide yes)
			(effects
				(font
					(size 1.27 1.27)
				)
				(justify mirror)
			)
		)
		(property "Value" "*"
			(at 0 -5.312918 270)
			(unlocked yes)
			(layer "B.Fab")
			(hide yes)
			(effects
				(font
					(size 1.27 1.016)
					(thickness 0.1524)
				)
				(justify mirror)
			)
		)
		(property "Device Type" "POLYSW-D5A6V-2-GP-U_DISCRET-GAA"
			(at 0 -7.344918 270)
			(unlocked yes)
			(layer "B.Fab")
			(hide yes)
			(effects
				(font
					(size 1.27 1.016)
					(thickness 0.1524)
				)
				(justify mirror)
			)
		)
		(duplicate_pad_numbers_are_jumpers no)
		(fp_line
			(start -1.0287 1.6637)
			(end -1.0287 -1.6637)
			(stroke
				(width 0.1524)
				(type default)
			)
			(layer "B.SilkS")
		)
		(fp_line
			(start 1.0287 1.6637)
			(end -1.0287 1.6637)
			(stroke
				(width 0.1524)
				(type default)
			)
			(layer "B.SilkS")
		)
		(fp_line
			(start -1.0287 -1.6637)
			(end 1.0287 -1.6637)
			(stroke
				(width 0.1524)
				(type default)
			)
			(layer "B.SilkS")
		)
		(fp_line
			(start 1.0287 -1.6637)
			(end 1.0287 1.6637)
			(stroke
				(width 0.1524)
				(type default)
			)
			(layer "B.SilkS")
		)
		(fp_rect
			(start 1.1049 1.7399)
			(end -1.1049 -1.7399)
			(stroke
				(width 0)
				(type default)
			)
			(fill no)
			(layer "B.CrtYd")
		)
		(fp_poly
			(pts
				(xy 1.1049 -1.7399) (xy -1.1049 -1.7399) (xy -1.1049 1.7399) (xy 1.1049 1.7399)
			)
			(stroke
				(width 0)
				(type default)
			)
			(fill no)
			(layer "B.Fab")
		)
		(pad "1" smd rect
			(at 0 -0.9398 90)
			(size 1.6002 0.9652)
			(layers "B.Cu" "B.Mask" "B.Paste")
			(net "P5V_VGA")
		)
		(pad "2" smd rect
			(at 0 0.9398 90)
			(size 1.6002 0.9652)
			(layers "B.Cu" "B.Mask" "B.Paste")
			(net "P5V_VGA_D")
		)
	)
	(footprint ""
		(layer "B.Cu")
		(at 102.080568 3.81 90)
		(property "Reference" "C8U12"
			(at 0 0 90)
			(layer "B.SilkS")
			(hide yes)
			(effects
				(font
					(size 1.27 1.27)
				)
				(justify mirror)
			)
		)
		(property "Value" ""
			(at 0 0 90)
			(layer "B.Fab")
			(effects
				(font
					(size 1.27 1.27)
				)
				(justify mirror)
			)
		)
		(duplicate_pad_numbers_are_jumpers no)
		(fp_poly
			(pts
				(xy 0.7239 -0.2159) (xy -0.7239 -0.2159) (xy -0.7239 1.9939) (xy 0.7239 1.9939)
			)
			(stroke
				(width 0)
				(type default)
			)
			(fill no)
			(layer "B.CrtYd")
		)
		(fp_line
			(start 0.7239 -0.2159)
			(end 0.7239 1.9939)
			(stroke
				(width 0.1)
				(type default)
			)
			(layer "B.Fab")
		)
		(fp_line
			(start -0.7239 -0.2159)
			(end 0.7239 -0.2159)
			(stroke
				(width 0.1)
				(type default)
			)
			(layer "B.Fab")
		)
		(fp_line
			(start 0.7239 1.9939)
			(end -0.7239 1.9939)
			(stroke
				(width 0.1)
				(type default)
			)
			(layer "B.Fab")
		)
		(fp_line
			(start -0.7239 1.9939)
			(end -0.7239 -0.2159)
			(stroke
				(width 0.1)
				(type default)
			)
			(layer "B.Fab")
		)
		(pad "1" smd rect
			(at 0 0 270)
			(size 1.27 1.016)
			(layers "B.Cu" "B.Mask" "B.Paste")
			(net "PVDDQ_GHJ")
		)
		(pad "2" smd rect
			(at 0 1.778 270)
			(size 1.27 1.016)
			(layers "B.Cu" "B.Mask" "B.Paste")
			(net "GND")
		)
		(zone
			(layer "B.Cu")
			(hatch none 0.5)
			(connect_pads
				(clearance 0)
			)
			(min_thickness 0.25)
			(keepout
				(tracks not_allowed)
				(vias allowed)
				(pads allowed)
				(copperpour not_allowed)
				(footprints allowed)
			)
			(placement
				(enabled no)
				(sheetname "")
			)
			(fill
				(thermal_gap 0.5)
				(thermal_bridge_width 0.5)
				(island_removal_mode 0)
			)
			(polygon
				(pts
					(xy 102.588568 3.175) (xy 102.588568 4.445) (xy 103.350568 4.445) (xy 103.350568 3.175)
				)
			)
		)
	)
	(footprint ""
		(layer "B.Cu")
		(at 485.267 -30.226)
		(property "Reference" "FB2T2"
			(at -1.34747 0.197104 270)
			(unlocked yes)
			(layer "B.SilkS")
			(effects
				(font
					(size 0.7874 0.5842)
					(thickness 0.1524)
				)
				(justify mirror)
			)
		)
		(property "Value" ""
			(at 0 0 0)
			(layer "B.Fab")
			(effects
				(font
					(size 1.27 1.27)
				)
				(justify mirror)
			)
		)
		(duplicate_pad_numbers_are_jumpers no)
		(fp_poly
			(pts
				(xy 0.7239 -0.26035) (xy -0.7239 -0.26035) (xy -0.7239 2.03835) (xy 0.7239 2.03835)
			)
			(stroke
				(width 0)
				(type default)
			)
			(fill no)
			(layer "B.CrtYd")
		)
		(fp_line
			(start -0.7239 -0.26035)
			(end -0.7239 2.03835)
			(stroke
				(width 0.1)
				(type default)
			)
			(layer "B.Fab")
		)
		(fp_line
			(start -0.7239 2.03835)
			(end 0.7239 2.03835)
			(stroke
				(width 0.1)
				(type default)
			)
			(layer "B.Fab")
		)
		(fp_line
			(start 0.7239 -0.26035)
			(end -0.7239 -0.26035)
			(stroke
				(width 0.1)
				(type default)
			)
			(layer "B.Fab")
		)
		(fp_line
			(start 0.7239 2.03835)
			(end 0.7239 -0.26035)
			(stroke
				(width 0.1)
				(type default)
			)
			(layer "B.Fab")
		)
		(pad "1" smd rect
			(at 0 0 180)
			(size 1.27 1.016)
			(layers "B.Cu" "B.Mask" "B.Paste")
			(net "P3V3_STBY")
		)
		(pad "2" smd rect
			(at 0 1.778 180)
			(size 1.27 1.016)
			(layers "B.Cu" "B.Mask" "B.Paste")
			(net "P3V3_STBY_MNG")
		)
		(zone
			(layer "B.Cu")
			(hatch none 0.5)
			(connect_pads
				(clearance 0)
			)
			(min_thickness 0.25)
			(keepout
				(tracks not_allowed)
				(vias allowed)
				(pads allowed)
				(copperpour not_allowed)
				(footprints allowed)
			)
			(placement
				(enabled no)
				(sheetname "")
			)
			(fill
				(thermal_gap 0.5)
				(thermal_bridge_width 0.5)
				(island_removal_mode 0)
			)
			(polygon
				(pts
					(xy 484.632 -29.718) (xy 484.632 -28.956) (xy 484.7209 -28.956) (xy 485.902 -28.956) (xy 485.902 -29.718)
				)
			)
		)
	)
	(footprint ""
		(layer "B.Cu")
		(at 384.53695 -111.85525 180)
		(property "Reference" "C3N2"
			(at 0 0 0)
			(layer "B.SilkS")
			(hide yes)
			(effects
				(font
					(size 1.27 1.27)
				)
				(justify mirror)
			)
		)
		(property "Value" ""
			(at 0 0 0)
			(layer "B.Fab")
			(effects
				(font
					(size 1.27 1.27)
				)
				(justify mirror)
			)
		)
		(duplicate_pad_numbers_are_jumpers no)
		(fp_rect
			(start 0.2794 0.9144)
			(end -0.2794 -0.1143)
			(stroke
				(width 0)
				(type default)
			)
			(fill no)
			(layer "B.CrtYd")
		)
		(fp_line
			(start 0.2794 0.9144)
			(end 0.2794 -0.1143)
			(stroke
				(width 0.1)
				(type default)
			)
			(layer "B.Fab")
		)
		(fp_line
			(start 0.2794 -0.1143)
			(end -0.2794 -0.1143)
			(stroke
				(width 0.1)
				(type default)
			)
			(layer "B.Fab")
		)
		(fp_line
			(start -0.2794 0.9144)
			(end 0.2794 0.9144)
			(stroke
				(width 0.1)
				(type default)
			)
			(layer "B.Fab")
		)
		(fp_line
			(start -0.2794 -0.1143)
			(end -0.2794 0.9144)
			(stroke
				(width 0.1)
				(type default)
			)
			(layer "B.Fab")
		)
		(pad "1" smd custom
			(at 0 0 90)
			(size 0.10414 0.10414)
			(layers "B.Cu" "B.Mask" "B.Paste")
			(net "PVNN_PCH_STBY")
			(options
				(clearance outline)
				(anchor circle)
			)
			(primitives
				(gr_poly
					(pts
						(xy -0.20828 -0.08636) (xy -0.20828 0.08636) (xy -0.08636 0.20828) (xy 0.086614 0.20828) (xy 0.20828 0.086614)
						(xy 0.20828 -0.08636) (xy 0.08636 -0.20828) (xy -0.08636 -0.20828)
					)
					(width 0)
					(fill yes)
				)
			)
		)
		(pad "2" smd custom
			(at 0 0.8001 90)
			(size 0.10414 0.10414)
			(layers "B.Cu" "B.Mask" "B.Paste")
			(net "GND")
			(options
				(clearance outline)
				(anchor circle)
			)
			(primitives
				(gr_poly
					(pts
						(xy -0.20828 -0.08636) (xy -0.20828 0.08636) (xy -0.08636 0.20828) (xy 0.086614 0.20828) (xy 0.20828 0.086614)
						(xy 0.20828 -0.08636) (xy 0.08636 -0.20828) (xy -0.08636 -0.20828)
					)
					(width 0)
					(fill yes)
				)
			)
		)
		(zone
			(layer "B.Cu")
			(hatch none 0.5)
			(connect_pads
				(clearance 0)
			)
			(min_thickness 0.25)
			(keepout
				(tracks not_allowed)
				(vias allowed)
				(pads allowed)
				(copperpour not_allowed)
				(footprints allowed)
			)
			(placement
				(enabled no)
				(sheetname "")
			)
			(fill
				(thermal_gap 0.5)
				(thermal_bridge_width 0.5)
				(island_removal_mode 0)
			)
			(polygon
				(pts
					(xy 384.44932 -112.0648) (xy 384.44932 -112.4458) (xy 384.62458 -112.4458) (xy 384.624834 -112.0648)
				)
			)
		)
		(zone
			(layer "B.Cu")
			(hatch none 0.5)
			(connect_pads
				(clearance 0)
			)
			(min_thickness 0.25)
			(keepout
				(tracks allowed)
				(vias not_allowed)
				(pads allowed)
				(copperpour not_allowed)
				(footprints allowed)
			)
			(placement
				(enabled no)
				(sheetname "")
			)
			(fill
				(thermal_gap 0.5)
				(thermal_bridge_width 0.5)
				(island_removal_mode 0)
			)
			(polygon
				(pts
					(xy 384.44932 -112.0648) (xy 384.44932 -112.4458) (xy 384.62458 -112.4458) (xy 384.624834 -112.0648)
				)
			)
		)
	)
	(footprint ""
		(layer "B.Cu")
		(at 397.637 -37.846 180)
		(property "Reference" "R8G2"
			(at 0 0 0)
			(layer "B.SilkS")
			(hide yes)
			(effects
				(font
					(size 1.27 1.27)
				)
				(justify mirror)
			)
		)
		(property "Value" ""
			(at 0 0 0)
			(layer "B.Fab")
			(effects
				(font
					(size 1.27 1.27)
				)
				(justify mirror)
			)
		)
		(duplicate_pad_numbers_are_jumpers no)
		(fp_poly
			(pts
				(xy 0.2794 -0.1016) (xy -0.2794 -0.1016) (xy -0.2794 0.9906) (xy 0.2794 0.9906)
			)
			(stroke
				(width 0)
				(type default)
			)
			(fill no)
			(layer "B.CrtYd")
		)
		(fp_line
			(start 0.2794 0.9906)
			(end -0.2794 0.9906)
			(stroke
				(width 0.1)
				(type default)
			)
			(layer "B.Fab")
		)
		(fp_line
			(start 0.2794 -0.1016)
			(end 0.2794 0.9906)
			(stroke
				(width 0.1)
				(type default)
			)
			(layer "B.Fab")
		)
		(fp_line
			(start -0.2794 0.9906)
			(end -0.2794 -0.1016)
			(stroke
				(width 0.1)
				(type default)
			)
			(layer "B.Fab")
		)
		(fp_line
			(start -0.2794 -0.1016)
			(end 0.2794 -0.1016)
			(stroke
				(width 0.1)
				(type default)
			)
			(layer "B.Fab")
		)
		(pad "1" smd rect
			(at 0 0)
			(size 0.508 0.508)
			(layers "B.Cu" "B.Mask" "B.Paste")
			(net "P3V3_STBY")
		)
		(pad "2" smd rect
			(at 0 0.889)
			(size 0.508 0.508)
			(layers "B.Cu" "B.Mask" "B.Paste")
			(net "FM_PCH_PWRBTN_OUT_N")
		)
		(zone
			(layer "B.Cu")
			(hatch none 0.5)
			(connect_pads
				(clearance 0)
			)
			(min_thickness 0.25)
			(keepout
				(tracks not_allowed)
				(vias allowed)
				(pads allowed)
				(copperpour not_allowed)
				(footprints allowed)
			)
			(placement
				(enabled no)
				(sheetname "")
			)
			(fill
				(thermal_gap 0.5)
				(thermal_bridge_width 0.5)
				(island_removal_mode 0)
			)
			(polygon
				(pts
					(xy 397.383 -38.481) (xy 397.891 -38.481) (xy 397.891 -38.1) (xy 397.383 -38.1)
				)
			)
		)
		(zone
			(layer "B.Cu")
			(hatch none 0.5)
			(connect_pads
				(clearance 0)
			)
			(min_thickness 0.25)
			(keepout
				(tracks allowed)
				(vias not_allowed)
				(pads allowed)
				(copperpour not_allowed)
				(footprints allowed)
			)
			(placement
				(enabled no)
				(sheetname "")
			)
			(fill
				(thermal_gap 0.5)
				(thermal_bridge_width 0.5)
				(island_removal_mode 0)
			)
			(polygon
				(pts
					(xy 397.383 -38.1) (xy 397.891 -38.1) (xy 397.891 -38.481) (xy 397.383 -38.481)
				)
			)
		)
	)
	(footprint ""
		(layer "B.Cu")
		(at 347.469206 2.694178 -90)
		(property "Reference" "C3U7"
			(at 0 0 90)
			(layer "B.SilkS")
			(hide yes)
			(effects
				(font
					(size 1.27 1.27)
				)
				(justify mirror)
			)
		)
		(property "Value" ""
			(at 0 0 90)
			(layer "B.Fab")
			(effects
				(font
					(size 1.27 1.27)
				)
				(justify mirror)
			)
		)
		(duplicate_pad_numbers_are_jumpers no)
		(fp_rect
			(start 0.7239 1.9939)
			(end -0.7239 -0.2159)
			(stroke
				(width 0)
				(type default)
			)
			(fill no)
			(layer "B.CrtYd")
		)
		(fp_line
			(start -0.7239 1.9939)
			(end -0.7239 -0.2159)
			(stroke
				(width 0.1)
				(type default)
			)
			(layer "B.Fab")
		)
		(fp_line
			(start 0.7239 1.9939)
			(end -0.7239 1.9939)
			(stroke
				(width 0.1)
				(type default)
			)
			(layer "B.Fab")
		)
		(fp_line
			(start -0.7239 -0.2159)
			(end 0.7239 -0.2159)
			(stroke
				(width 0.1)
				(type default)
			)
			(layer "B.Fab")
		)
		(fp_line
			(start 0.7239 -0.2159)
			(end 0.7239 1.9939)
			(stroke
				(width 0.1)
				(type default)
			)
			(layer "B.Fab")
		)
		(pad "1" smd rect
			(at 0 0 90)
			(size 1.27 1.016)
			(layers "B.Cu" "B.Mask" "B.Paste")
			(net "VR_FET_SW_P12V_STBY_PVDDQ_ABC")
		)
		(pad "2" smd rect
			(at 0 1.778 90)
			(size 1.27 1.016)
			(layers "B.Cu" "B.Mask" "B.Paste")
			(net "GND")
		)
		(zone
			(layer "B.Cu")
			(hatch none 0.5)
			(connect_pads
				(clearance 0)
			)
			(min_thickness 0.25)
			(keepout
				(tracks not_allowed)
				(vias allowed)
				(pads allowed)
				(copperpour not_allowed)
				(footprints allowed)
			)
			(placement
				(enabled no)
				(sheetname "")
			)
			(fill
				(thermal_gap 0.5)
				(thermal_bridge_width 0.5)
				(island_removal_mode 0)
			)
			(polygon
				(pts
					(xy 346.199206 3.329178) (xy 346.961206 3.329178) (xy 346.961206 2.059178) (xy 346.199206 2.059178)
				)
			)
		)
	)
	(footprint ""
		(layer "B.Cu")
		(at 205.74 -105.537 -90)
		(property "Reference" "R6N11"
			(at 0 0 90)
			(layer "B.SilkS")
			(hide yes)
			(effects
				(font
					(size 1.27 1.27)
				)
				(justify mirror)
			)
		)
		(property "Value" ""
			(at 0 0 90)
			(layer "B.Fab")
			(effects
				(font
					(size 1.27 1.27)
				)
				(justify mirror)
			)
		)
		(duplicate_pad_numbers_are_jumpers no)
		(fp_poly
			(pts
				(xy 0.2794 -0.1016) (xy -0.2794 -0.1016) (xy -0.2794 0.9906) (xy 0.2794 0.9906)
			)
			(stroke
				(width 0)
				(type default)
			)
			(fill no)
			(layer "B.CrtYd")
		)
		(fp_line
			(start -0.2794 0.9906)
			(end -0.2794 -0.1016)
			(stroke
				(width 0.1)
				(type default)
			)
			(layer "B.Fab")
		)
		(fp_line
			(start 0.2794 0.9906)
			(end -0.2794 0.9906)
			(stroke
				(width 0.1)
				(type default)
			)
			(layer "B.Fab")
		)
		(fp_line
			(start -0.2794 -0.1016)
			(end 0.2794 -0.1016)
			(stroke
				(width 0.1)
				(type default)
			)
			(layer "B.Fab")
		)
		(fp_line
			(start 0.2794 -0.1016)
			(end 0.2794 0.9906)
			(stroke
				(width 0.1)
				(type default)
			)
			(layer "B.Fab")
		)
		(pad "1" smd rect
			(at 0 0 90)
			(size 0.508 0.508)
			(layers "B.Cu" "B.Mask" "B.Paste")
			(net "SVID_DIO0_CPU0")
		)
		(pad "2" smd rect
			(at 0 0.889 90)
			(size 0.508 0.508)
			(layers "B.Cu" "B.Mask" "B.Paste")
			(net "SVID_DIO0_CPU0_R")
		)
		(zone
			(layer "B.Cu")
			(hatch none 0.5)
			(connect_pads
				(clearance 0)
			)
			(min_thickness 0.25)
			(keepout
				(tracks not_allowed)
				(vias allowed)
				(pads allowed)
				(copperpour not_allowed)
				(footprints allowed)
			)
			(placement
				(enabled no)
				(sheetname "")
			)
			(fill
				(thermal_gap 0.5)
				(thermal_bridge_width 0.5)
				(island_removal_mode 0)
			)
			(polygon
				(pts
					(xy 205.105 -105.283) (xy 205.105 -105.791) (xy 205.486 -105.791) (xy 205.486 -105.283)
				)
			)
		)
		(zone
			(layer "B.Cu")
			(hatch none 0.5)
			(connect_pads
				(clearance 0)
			)
			(min_thickness 0.25)
			(keepout
				(tracks allowed)
				(vias not_allowed)
				(pads allowed)
				(copperpour not_allowed)
				(footprints allowed)
			)
			(placement
				(enabled no)
				(sheetname "")
			)
			(fill
				(thermal_gap 0.5)
				(thermal_bridge_width 0.5)
				(island_removal_mode 0)
			)
			(polygon
				(pts
					(xy 205.486 -105.283) (xy 205.486 -105.791) (xy 205.105 -105.791) (xy 205.105 -105.283)
				)
			)
		)
	)
)
